# S9S_MB_2U (Grand Teton) — schematic netlist excerpt (pin names and nets, part order shuffled) for the footprints in the layout excerpt that follows; sources: Cadence DE-HDL packaged netlist, KiCad conversion of 03242023_DA0F0TMBIJ0_F0T_Motherboard_J_brd_V01_OCP.brd

R2589  Q_RES  1K 1% CHIP  pkg 0402LF  page 266 : A = P3V3_AUX ; B = PVCCIN_CPU0_VR_FAULT
PC491_P1_8  Q_CAP  22UF 16V 20% X6S  pkg C0805  page 288 : A = SW_P12V_PVCCIN_CPU1_FLT ; B = GND
C481  Q_CAP  47UF 4V 20% X6S  pkg C0805  page 79 : A = PVCCINFAON_CPU1 ; B = GND

(kicad_pcb
	(version 20260206)
	(generator "pcbnew")
	(generator_version "10.0")
	(general
		(thickness 1.6)
		(legacy_teardrops no)
	)
	(paper "A4")
	(title_block
		(title "03242023_DA0F0TMBIJ0_F0T_Motherboard_J_brd_V01_OCP.brd")
		(comment 1 "Grand Teton / footprints 5281-5283 of 6105")
	)
	(layers
		(0 "F.Cu" signal "TOP")
		(4 "In1.Cu" signal "GND")
		(6 "In2.Cu" signal "IN1")
		(8 "In3.Cu" signal "GND1")
		(10 "In4.Cu" signal "IN2")
		(12 "In5.Cu" signal "GND2")
		(14 "In6.Cu" signal "IN3")
		(16 "In7.Cu" signal "GND3")
		(18 "In8.Cu" signal "VCC")
		(20 "In9.Cu" signal "VCC1")
		(22 "In10.Cu" signal "GND4")
		(24 "In11.Cu" signal "IN4")
		(26 "In12.Cu" signal "GND5")
		(28 "In13.Cu" signal "IN5")
		(30 "In14.Cu" signal "GND6")
		(32 "In15.Cu" signal "IN6")
		(34 "In16.Cu" signal "GND7")
		(2 "B.Cu" signal "BOTTOM")
		(9 "F.Adhes" user "F.Adhesive")
		(11 "B.Adhes" user "B.Adhesive")
		(13 "F.Paste" user "Package Geometry/Pastemask Top")
		(15 "B.Paste" user "Package Geometry/Pastemask Bottom")
		(5 "F.SilkS" user "Ref Des/Silkscreen Top")
		(7 "B.SilkS" user "Ref Des/Silkscreen Bottom")
		(1 "F.Mask" user "Board Geometry/Soldermask Top")
		(3 "B.Mask" user "Board Geometry/Soldermask Bottom")
		(17 "Dwgs.User" user "User.Drawings")
		(19 "Cmts.User" user "User.Comments")
		(21 "Eco1.User" user "User.Eco1")
		(23 "Eco2.User" user "User.Eco2")
		(25 "Edge.Cuts" user "Board Geometry/Outline")
		(27 "Margin" user)
		(31 "F.CrtYd" user "Package Geometry/Place Bound Top")
		(29 "B.CrtYd" user "Package Geometry/Place Bound Bottom")
		(35 "F.Fab" user "Ref Des/Assembly Top")
		(33 "B.Fab" user "Ref Des/Assembly Bottom")
	)
	(footprint ""
		(layer "B.Cu")
		(at 363.2962 -356.094792)
		(property "Reference" "R2589"
			(at 0 0 0)
			(layer "B.SilkS")
			(hide yes)
			(effects
				(font
					(size 1.27 1.27)
				)
				(justify mirror)
			)
		)
		(property "Value" ""
			(at 0 0 0)
			(layer "B.Fab")
			(effects
				(font
					(size 1.27 1.27)
				)
				(justify mirror)
			)
		)
		(duplicate_pad_numbers_are_jumpers no)
		(fp_line
			(start -0.7874 -0.4064)
			(end -0.7874 0.4064)
			(stroke
				(width 0.1524)
				(type default)
			)
			(layer "B.SilkS")
		)
		(fp_line
			(start -0.7874 0.4064)
			(end 0.7874 0.4064)
			(stroke
				(width 0.1524)
				(type default)
			)
			(layer "B.SilkS")
		)
		(fp_line
			(start 0.7874 -0.4064)
			(end -0.7874 -0.4064)
			(stroke
				(width 0.1524)
				(type default)
			)
			(layer "B.SilkS")
		)
		(fp_line
			(start 0.7874 0.4064)
			(end 0.7874 -0.4064)
			(stroke
				(width 0.1524)
				(type default)
			)
			(layer "B.SilkS")
		)
		(fp_line
			(start -0.67945 -0.3048)
			(end -0.67945 0.3048)
			(stroke
				(width 0.1)
				(type default)
			)
			(layer "B.Fab")
		)
		(fp_line
			(start -0.67945 0.3048)
			(end -0.120396 0.3048)
			(stroke
				(width 0.1)
				(type default)
			)
			(layer "B.Fab")
		)
		(fp_line
			(start -0.12065 -0.3048)
			(end -0.67945 -0.3048)
			(stroke
				(width 0.1)
				(type default)
			)
			(layer "B.Fab")
		)
		(fp_line
			(start -0.12065 -0.2794)
			(end -0.12065 -0.3048)
			(stroke
				(width 0.1)
				(type default)
			)
			(layer "B.Fab")
		)
		(fp_line
			(start -0.120396 0.2794)
			(end 0.12065 0.2794)
			(stroke
				(width 0.1)
				(type default)
			)
			(layer "B.Fab")
		)
		(fp_line
			(start -0.120396 0.3048)
			(end -0.120396 0.2794)
			(stroke
				(width 0.1)
				(type default)
			)
			(layer "B.Fab")
		)
		(fp_line
			(start 0.12065 -0.305054)
			(end 0.12065 -0.2794)
			(stroke
				(width 0.1)
				(type default)
			)
			(layer "B.Fab")
		)
		(fp_line
			(start 0.12065 -0.2794)
			(end -0.12065 -0.2794)
			(stroke
				(width 0.1)
				(type default)
			)
			(layer "B.Fab")
		)
		(fp_line
			(start 0.12065 0.2794)
			(end 0.12065 0.3048)
			(stroke
				(width 0.1)
				(type default)
			)
			(layer "B.Fab")
		)
		(fp_line
			(start 0.12065 0.3048)
			(end 0.67945 0.3048)
			(stroke
				(width 0.1)
				(type default)
			)
			(layer "B.Fab")
		)
		(fp_line
			(start 0.67945 -0.305054)
			(end 0.12065 -0.305054)
			(stroke
				(width 0.1)
				(type default)
			)
			(layer "B.Fab")
		)
		(fp_line
			(start 0.67945 0.3048)
			(end 0.67945 -0.305054)
			(stroke
				(width 0.1)
				(type default)
			)
			(layer "B.Fab")
		)
		(pad "1" smd circle
			(at 0.40005 0 180)
			(size 0 0)
			(layers "B.Cu" "B.Mask" "B.Paste")
			(net "P3V3_AUX")
		)
		(pad "2" smd circle
			(at -0.40005 0 180)
			(size 0 0)
			(layers "B.Cu" "B.Mask" "B.Paste")
			(net "PVCCIN_CPU0_VR_FAULT")
		)
	)
	(footprint ""
		(layer "B.Cu")
		(at 139.021058 -347.008704 -90)
		(property "Reference" "PC491_P1_8"
			(at 0 0 90)
			(layer "B.SilkS")
			(hide yes)
			(effects
				(font
					(size 1.27 1.27)
				)
				(justify mirror)
			)
		)
		(property "Value" ""
			(at 0 0 90)
			(layer "B.Fab")
			(effects
				(font
					(size 1.27 1.27)
				)
				(justify mirror)
			)
		)
		(duplicate_pad_numbers_are_jumpers no)
		(fp_line
			(start -1.524 0.762)
			(end 1.524 0.762)
			(stroke
				(width 0.1524)
				(type default)
			)
			(layer "B.SilkS")
		)
		(fp_line
			(start 1.524 0.762)
			(end 1.524 -0.762)
			(stroke
				(width 0.1524)
				(type default)
			)
			(layer "B.SilkS")
		)
		(fp_line
			(start -1.524 -0.762)
			(end -1.524 0.762)
			(stroke
				(width 0.1524)
				(type default)
			)
			(layer "B.SilkS")
		)
		(fp_line
			(start 1.524 -0.762)
			(end -1.524 -0.762)
			(stroke
				(width 0.1524)
				(type default)
			)
			(layer "B.SilkS")
		)
		(fp_line
			(start -1.1049 0.724916)
			(end -1.1049 -0.724916)
			(stroke
				(width 0.1)
				(type default)
			)
			(layer "B.Fab")
		)
		(fp_line
			(start 1.1049 0.724916)
			(end -1.1049 0.724916)
			(stroke
				(width 0.1)
				(type default)
			)
			(layer "B.Fab")
		)
		(fp_line
			(start -1.1049 -0.724916)
			(end 1.1049 -0.724916)
			(stroke
				(width 0.1)
				(type default)
			)
			(layer "B.Fab")
		)
		(fp_line
			(start 1.1049 -0.724916)
			(end 1.1049 0.724916)
			(stroke
				(width 0.1)
				(type default)
			)
			(layer "B.Fab")
		)
		(pad "1" smd rect
			(at 0.889 0 270)
			(size 1.016 1.27)
			(layers "B.Cu" "B.Mask" "B.Paste")
			(net "SW_P12V_PVCCIN_CPU1_FLT")
		)
		(pad "2" smd rect
			(at -0.889 0 270)
			(size 1.016 1.27)
			(layers "B.Cu" "B.Mask" "B.Paste")
			(net "GND")
		)
	)
	(footprint ""
		(layer "B.Cu")
		(at 118.158006 -212.049868)
		(property "Reference" "C481"
			(at 0 0 0)
			(layer "B.SilkS")
			(hide yes)
			(effects
				(font
					(size 1.27 1.27)
				)
				(justify mirror)
			)
		)
		(property "Value" ""
			(at 0 0 0)
			(layer "B.Fab")
			(effects
				(font
					(size 1.27 1.27)
				)
				(justify mirror)
			)
		)
		(duplicate_pad_numbers_are_jumpers no)
		(fp_line
			(start -1.524 -0.762)
			(end -1.524 0.762)
			(stroke
				(width 0.1524)
				(type default)
			)
			(layer "B.SilkS")
		)
		(fp_line
			(start -1.524 0.762)
			(end 1.524 0.762)
			(stroke
				(width 0.1524)
				(type default)
			)
			(layer "B.SilkS")
		)
		(fp_line
			(start 1.524 -0.762)
			(end -1.524 -0.762)
			(stroke
				(width 0.1524)
				(type default)
			)
			(layer "B.SilkS")
		)
		(fp_line
			(start 1.524 0.762)
			(end 1.524 -0.762)
			(stroke
				(width 0.1524)
				(type default)
			)
			(layer "B.SilkS")
		)
		(fp_line
			(start -1.1049 -0.724916)
			(end 1.1049 -0.724916)
			(stroke
				(width 0.1)
				(type default)
			)
			(layer "B.Fab")
		)
		(fp_line
			(start -1.1049 0.724916)
			(end -1.1049 -0.724916)
			(stroke
				(width 0.1)
				(type default)
			)
			(layer "B.Fab")
		)
		(fp_line
			(start 1.1049 -0.724916)
			(end 1.1049 0.724916)
			(stroke
				(width 0.1)
				(type default)
			)
			(layer "B.Fab")
		)
		(fp_line
			(start 1.1049 0.724916)
			(end -1.1049 0.724916)
			(stroke
				(width 0.1)
				(type default)
			)
			(layer "B.Fab")
		)
		(pad "1" smd rect
			(at 0.889 0)
			(size 1.016 1.27)
			(layers "B.Cu" "B.Mask" "B.Paste")
			(net "PVCCINFAON_CPU1")
		)
		(pad "2" smd rect
			(at -0.889 0)
			(size 1.016 1.27)
			(layers "B.Cu" "B.Mask" "B.Paste")
			(net "GND")
		)
	)
)
